#ISCELL
  mstr_misc dns *
  *
#ISCELL
  mstr_symbols design_note *
  *
#ISCELL
  mstr_symbols intel_corp_bpage *
  *
#ISCELL
  mstr_standard offpage *
  page209_i1
#CELL
  mstr_discrete res *
  page209_i10
#CELL
  mstr_discrete res *
  page209_i11
#ISCELL
  mstr_symbols gnd *
  page209_i12
#ISCELL
  mstr_standard offpage *
  page209_i13
#ISCELL
  mstr_standard offpage *
  page209_i14
#CELL
  mstr_discrete res *
  page209_i15
#CELL
  mstr_discrete cap *
  page209_i16
#CELL
  dev_discrete cap_a *
  page209_i17
#CELL
  mstr_discrete cap *
  page209_i18
#ISCELL
  mstr_symbols pvccin_cpu1 *
  page209_i19
#ISCELL
  mstr_standard offpage *
  page209_i2
#CELL
  mstr_discrete cap *
  page209_i20
#CELL
  dev_discrete cap_a *
  page209_i21
#CELL
  mstr_discrete cap *
  page209_i22
#ISCELL
  mstr_symbols vcc_core *
  page209_i23
#CELL
  mstr_discrete res *
  page209_i24
#ISCELL
  mstr_symbols gnd *
  page209_i26
#ISCELL
  mstr_standard offpage *
  page209_i27
#ISCELL
  mstr_symbols gnd *
  page209_i29
#CELL
  mstr_discrete res *
  page209_i3
#CELL
  dev_discrete cap_a *
  page209_i30
#CELL
  mstr_discrete inductor *
  page209_i32
#ISCELL
  mstr_symbols gnd *
  page209_i34
#CELL
  mstr_discrete capp *
  page209_i35
#ISCELL
  mstr_symbols gnd *
  page209_i36
#CELL
  mstr_discrete capp *
  page209_i37
#CELL
  mstr_discrete capp *
  page209_i38
#CELL
  mstr_discrete res *
  page209_i39
#ISCELL
  mstr_symbols gnd *
  page209_i4
#CELL
  mstr_discrete inductor *
  page209_i40
#ISCELL
  mstr_symbols gnd *
  page209_i41
#CELL
  dev_discrete cap_a *
  page209_i42
#ISCELL
  mstr_symbols pvccin_cpu1 *
  page209_i43
#ISCELL
  mstr_standard offpage *
  page209_i44
#ISCELL
  mstr_symbols vcc_core *
  page209_i45
#ISCELL
  mstr_standard offpage *
  page209_i49
#CELL
  mstr_discrete cap *
  page209_i5
#CELL
  mstr_analog adm4073 *
  page209_i52
#ISCELL
  mstr_symbols p12v_stby *
  page209_i53
#ISCELL
  mstr_symbols p5v_stby *
  page209_i54
#CELL
  dev_discrete cap_a *
  page209_i55
#CELL
  mstr_discrete ir354xx *
  page209_i56
#ISCELL
  mstr_standard offpage *
  page209_i57
#ISCELL
  mstr_standard offpage *
  page209_i58
#CELL
  mstr_discrete res *
  page209_i59
#ISCELL
  mstr_symbols gnd *
  page209_i60
#CELL
  dev_discrete cap_a *
  page209_i62
#ISCELL
  mstr_symbols gnd *
  page209_i63
#CELL
  w_hdl sc2k2p50v3kx-gp *
  page209_i64
#ISCELL
  mstr_symbols gnd *
  page209_i65
#CELL
  w_hdl 3d01r5f-gp *
  page209_i66
#CELL
  mstr_discrete cap *
  page209_i67
#ISCELL
  mstr_symbols gnd *
  page209_i68
#CELL
  mstr_discrete res *
  page209_i69
#CELL
  mstr_discrete cap *
  page209_i7
#CELL
  mstr_discrete cap *
  page209_i8
#CELL
  mstr_discrete res *
  page209_i9
